FILE_TYPE = MACRO_DRAWING;
SET COLOR_WIRE YELLOW;
SET COLOR_PROP ORANGE;
SET COLOR_DOT WHITE;
SET COLOR_ARC YELLOW;
SET COLOR_BODY GREEN;
SET COLOR_NOTE PURPLE;
SET PROP_DISPLAY VALUE;
SET PAGE_NUMBER P112;
FORCEADD Q_RES..1
(-7125 4975);
FORCEPROP 1 LAST LOCATION R6154
J 0
(-7400 4975);
DISPLAY 0.808511 (-7400 4975);
FORCEPROP 0 LAST $SEC 1
J 0
(-6775 5025);
DISPLAY 0.680851 (-6775 5025);
PAINT MONO (-6775 5025);
DISPLAY INVISIBLE (-6775 5025);
FORCEPROP 0 LAST CDS_SEC 1
J 0
(-6775 5025);
DISPLAY 0.680851 (-6775 5025);
DISPLAY INVISIBLE (-6775 5025);
FORCEPROP 1 LASTPIN (-7225 4975) $PN 1
J 0
(-7213 4987);
DISPLAY 0.787234 (-7213 4987);
PAINT MONO (-7213 4987);
FORCEPROP 1 LASTPIN (-7025 4975) $PN 2
J 0
(-7063 4987);
DISPLAY 0.787234 (-7063 4987);
PAINT MONO (-7063 4987);
FORCEPROP 1 LAST MATERIAL CHIP
J 0
(-6850 4975);
DISPLAY 0.808511 (-6850 4975);
FORCEPROP 1 LAST PACK_TYPE 0201LF
J 0
(-6650 4975);
DISPLAY 0.808511 (-6650 4975);
FORCEPROP 2 LAST ROOM PCIE REDRIVER BOM2
J 0
(-7375 5050);
DISPLAY 0.680851 (-7375 5050);
PAINT RED (-7375 5050);
FORCEPROP 1 LAST VALUE 0
J 2
(-6925 4975);
DISPLAY 0.808511 (-6925 4975);
FORCEPROP 1 LAST TOLERANCE 5%
J 0
(-7300 5100);
DISPLAY 0.978723 (-7300 5100);
DISPLAY INVISIBLE (-7300 5100);
FORCEPROP 1 LAST WATTAGE 1/20W
J 2
(-6850 5100);
DISPLAY 0.978723 (-6850 5100);
DISPLAY INVISIBLE (-6850 5100);
FORCEPROP 2 LAST CDS_LIB pure_quanta
J 0
(-7125 4975);
DISPLAY INVISIBLE (-7125 4975);
FORCEPROP 1 LAST PATH I1
J 0
(-7175 5125);
DISPLAY 0.978723 (-7175 5125);
PAINT WHITE (-7175 5125);
DISPLAY INVISIBLE (-7175 5125);
FORCEPROP 1 LAST PART_NUMBER CS00001JE10
J 0
(-7350 5150);
DISPLAY 0.978723 (-7350 5150);
DISPLAY INVISIBLE (-7350 5150);
FORCEADD OFFPAGE..4
R 2
(-8225 5275);
FORCEPROP 2 LAST $XR0 150 
J 0
(-8477 5275);
DISPLAY 0.638298 (-8477 5275);
PAINT MONO (-8477 5275);
FORCEPROP 2 LAST CDS_LIB standard
J 0
(-8225 5275);
DISPLAY INVISIBLE (-8225 5275);
FORCEPROP 1 LAST OFFPAGE TRUE
J 2
(-8550 5150);
DISPLAY 0.872340 (-8550 5150);
PAINT GREEN (-8550 5150);
DISPLAY INVISIBLE (-8550 5150);
FORCEPROP 1 LAST COMMENT_BODY TRUE
J 2
(-8200 5175);
DISPLAY 0.872340 (-8200 5175);
PAINT GREEN (-8200 5175);
DISPLAY INVISIBLE (-8200 5175);
FORCEPROP 2 LAST PATH I10
J 0
(-8175 5350);
DISPLAY 0.680851 (-8175 5350);
DISPLAY INVISIBLE (-8175 5350);
FORCEADD Q_CAP..2
(-2550 4275);
FORCEPROP 1 LAST LOCATION C1868
J 1
(-2725 4275);
DISPLAY 0.510638 (-2725 4275);
FORCEPROP 0 LAST $SEC 1
J 0
(-2725 4300);
DISPLAY 0.680851 (-2725 4300);
PAINT MONO (-2725 4300);
DISPLAY INVISIBLE (-2725 4300);
FORCEPROP 0 LAST CDS_SEC 1
J 0
(-2725 4300);
DISPLAY 0.680851 (-2725 4300);
DISPLAY INVISIBLE (-2725 4300);
FORCEPROP 1 LASTPIN (-2650 4275) $PN 1
J 0
(-2660 4290);
DISPLAY 0.787234 (-2660 4290);
PAINT MONO (-2660 4290);
FORCEPROP 1 LASTPIN (-2450 4275) $PN 2
J 0
(-2465 4290);
DISPLAY 0.787234 (-2465 4290);
PAINT MONO (-2465 4290);
FORCEPROP 1 LAST PACK_TYPE 0402
J 1
(-2375 4450);
DISPLAY 0.638298 (-2375 4450);
FORCEPROP 2 LAST ROOM PCIE REDRIVER BOM1
J 0
(-2750 4350);
DISPLAY 0.680851 (-2750 4350);
PAINT RED (-2750 4350);
FORCEPROP 1 LAST VALUE 0.1UF
J 2
(-2475 4450);
DISPLAY 0.638298 (-2475 4450);
FORCEPROP 2 LAST CDS_LIB pure_quanta
J 0
(-2550 4275);
DISPLAY INVISIBLE (-2550 4275);
FORCEPROP 1 LAST MATERIAL X7R
J 0
(-2525 4025);
DISPLAY 0.638298 (-2525 4025);
DISPLAY INVISIBLE (-2525 4025);
FORCEPROP 1 LAST TOLERANCE 10%
J 2
(-2525 4025);
DISPLAY 0.638298 (-2525 4025);
DISPLAY INVISIBLE (-2525 4025);
FORCEPROP 1 LAST VOLTAGE 25V
J 0
(-2525 4075);
DISPLAY 0.638298 (-2525 4075);
DISPLAY INVISIBLE (-2525 4075);
FORCEPROP 1 LAST PATH I11
J 0
(-2550 4475);
DISPLAY 0.978723 (-2550 4475);
PAINT WHITE (-2550 4475);
DISPLAY INVISIBLE (-2550 4475);
FORCEPROP 1 LAST PART_NUMBER CH4104K1B00
J 1
(-2475 4500);
DISPLAY 0.510638 (-2475 4500);
DISPLAY INVISIBLE (-2475 4500);
FORCEADD Q_CAP..2
(-2550 4225);
FORCEPROP 1 LAST LOCATION C1869
J 1
(-2725 4225);
DISPLAY 0.510638 (-2725 4225);
FORCEPROP 0 LAST $SEC 1
J 0
(-2725 4250);
DISPLAY 0.680851 (-2725 4250);
PAINT MONO (-2725 4250);
DISPLAY INVISIBLE (-2725 4250);
FORCEPROP 0 LAST CDS_SEC 1
J 0
(-2725 4250);
DISPLAY 0.680851 (-2725 4250);
DISPLAY INVISIBLE (-2725 4250);
FORCEPROP 1 LASTPIN (-2650 4225) $PN 1
J 0
(-2660 4240);
DISPLAY 0.787234 (-2660 4240);
PAINT MONO (-2660 4240);
FORCEPROP 1 LASTPIN (-2450 4225) $PN 2
J 0
(-2465 4240);
DISPLAY 0.787234 (-2465 4240);
PAINT MONO (-2465 4240);
FORCEPROP 2 LAST ROOM PCIE REDRIVER BOM1
J 0
(-2775 4150);
DISPLAY 0.680851 (-2775 4150);
PAINT RED (-2775 4150);
FORCEPROP 1 LAST VOLTAGE 25V
J 0
(-2525 4150);
DISPLAY 0.638298 (-2525 4150);
DISPLAY INVISIBLE (-2525 4150);
FORCEPROP 1 LAST VALUE 0.1UF
J 2
(-2525 4150);
DISPLAY 0.638298 (-2525 4150);
DISPLAY INVISIBLE (-2525 4150);
FORCEPROP 1 LAST MATERIAL X7R
J 0
(-2525 4100);
DISPLAY 0.638298 (-2525 4100);
DISPLAY INVISIBLE (-2525 4100);
FORCEPROP 1 LAST PACK_TYPE 0402
J 1
(-2525 4050);
DISPLAY 0.638298 (-2525 4050);
DISPLAY INVISIBLE (-2525 4050);
FORCEPROP 1 LAST TOLERANCE 10%
J 2
(-2525 4100);
DISPLAY 0.638298 (-2525 4100);
DISPLAY INVISIBLE (-2525 4100);
FORCEPROP 2 LAST CDS_LIB pure_quanta
J 0
(-2550 4225);
DISPLAY INVISIBLE (-2550 4225);
FORCEPROP 1 LAST PATH I12
J 0
(-2550 4425);
DISPLAY 0.978723 (-2550 4425);
PAINT WHITE (-2550 4425);
DISPLAY INVISIBLE (-2550 4425);
FORCEPROP 1 LAST PART_NUMBER CH4104K1B00
J 1
(-2525 4025);
DISPLAY 0.510638 (-2525 4025);
DISPLAY INVISIBLE (-2525 4025);
FORCEADD Q_CAP..2
(-2700 5250);
FORCEPROP 1 LAST LOCATION C1870
J 1
(-2875 5250);
DISPLAY 0.510638 (-2875 5250);
FORCEPROP 0 LAST $SEC 1
J 0
(-2825 5275);
DISPLAY 0.680851 (-2825 5275);
PAINT MONO (-2825 5275);
DISPLAY INVISIBLE (-2825 5275);
FORCEPROP 0 LAST CDS_SEC 1
J 0
(-2825 5275);
DISPLAY 0.680851 (-2825 5275);
DISPLAY INVISIBLE (-2825 5275);
FORCEPROP 1 LASTPIN (-2800 5250) $PN 1
J 0
(-2810 5265);
DISPLAY 0.787234 (-2810 5265);
PAINT MONO (-2810 5265);
FORCEPROP 1 LASTPIN (-2600 5250) $PN 2
J 0
(-2615 5265);
DISPLAY 0.787234 (-2615 5265);
PAINT MONO (-2615 5265);
FORCEPROP 2 LAST ROOM PCIE REDRIVER BOM1
J 0
(-2900 5300);
DISPLAY 0.680851 (-2900 5300);
PAINT RED (-2900 5300);
FORCEPROP 2 LAST CDS_LIB pure_quanta
J 0
(-2700 5250);
DISPLAY INVISIBLE (-2700 5250);
FORCEPROP 1 LAST MATERIAL X7R
J 0
(-2675 5000);
DISPLAY 0.638298 (-2675 5000);
DISPLAY INVISIBLE (-2675 5000);
FORCEPROP 1 LAST PACK_TYPE 0402
J 1
(-2675 4950);
DISPLAY 0.638298 (-2675 4950);
DISPLAY INVISIBLE (-2675 4950);
FORCEPROP 1 LAST TOLERANCE 10%
J 2
(-2675 5000);
DISPLAY 0.638298 (-2675 5000);
DISPLAY INVISIBLE (-2675 5000);
FORCEPROP 1 LAST VALUE 0.1UF
J 2
(-2675 5050);
DISPLAY 0.638298 (-2675 5050);
DISPLAY INVISIBLE (-2675 5050);
FORCEPROP 1 LAST VOLTAGE 25V
J 0
(-2675 5050);
DISPLAY 0.638298 (-2675 5050);
DISPLAY INVISIBLE (-2675 5050);
FORCEPROP 1 LAST PATH I13
J 0
(-2700 5450);
DISPLAY 0.978723 (-2700 5450);
PAINT WHITE (-2700 5450);
DISPLAY INVISIBLE (-2700 5450);
FORCEPROP 1 LAST PART_NUMBER CH4104K1B00
J 1
(-2675 4925);
DISPLAY 0.510638 (-2675 4925);
DISPLAY INVISIBLE (-2675 4925);
FORCEADD Q_CAP..2
(-2700 5200);
FORCEPROP 1 LAST LOCATION C1871
J 1
(-2875 5200);
DISPLAY 0.510638 (-2875 5200);
FORCEPROP 0 LAST $SEC 1
J 0
(-2700 5475);
DISPLAY 0.680851 (-2700 5475);
PAINT MONO (-2700 5475);
DISPLAY INVISIBLE (-2700 5475);
FORCEPROP 0 LAST CDS_SEC 1
J 0
(-2700 5475);
DISPLAY 0.680851 (-2700 5475);
DISPLAY INVISIBLE (-2700 5475);
FORCEPROP 1 LASTPIN (-2800 5200) $PN 1
J 0
(-2810 5215);
DISPLAY 0.787234 (-2810 5215);
PAINT MONO (-2810 5215);
FORCEPROP 1 LASTPIN (-2600 5200) $PN 2
J 0
(-2615 5215);
DISPLAY 0.787234 (-2615 5215);
PAINT MONO (-2615 5215);
FORCEPROP 1 LAST VALUE 0.1UF
J 2
(-2675 5500);
DISPLAY 0.638298 (-2675 5500);
FORCEPROP 1 LAST TOLERANCE 10%
J 2
(-2575 5450);
DISPLAY 0.638298 (-2575 5450);
FORCEPROP 1 LAST VOLTAGE 25V
J 0
(-2675 5500);
DISPLAY 0.638298 (-2675 5500);
FORCEPROP 1 LAST MATERIAL X7R
J 0
(-2575 5500);
DISPLAY 0.638298 (-2575 5500);
FORCEPROP 1 LAST PACK_TYPE 0402
J 1
(-2750 5450);
DISPLAY 0.638298 (-2750 5450);
FORCEPROP 2 LAST ROOM PCIE REDRIVER BOM1
J 0
(-2900 5125);
DISPLAY 0.680851 (-2900 5125);
PAINT RED (-2900 5125);
FORCEPROP 2 LAST CDS_LIB pure_quanta
J 0
(-2700 5200);
DISPLAY INVISIBLE (-2700 5200);
FORCEPROP 1 LAST PATH I14
J 0
(-2700 5400);
DISPLAY 0.978723 (-2700 5400);
PAINT WHITE (-2700 5400);
DISPLAY INVISIBLE (-2700 5400);
FORCEPROP 1 LAST PART_NUMBER CH4104K1B00
J 1
(-2700 5550);
DISPLAY 0.510638 (-2700 5550);
DISPLAY INVISIBLE (-2700 5550);
FORCEADD OFFPAGE..4
R 2
(-8300 4150);
FORCEPROP 2 LAST $XR0 122 
J 0
(-8552 4150);
DISPLAY 0.638298 (-8552 4150);
PAINT MONO (-8552 4150);
FORCEPROP 2 LAST CDS_LIB standard
J 0
(-8300 4150);
DISPLAY INVISIBLE (-8300 4150);
FORCEPROP 1 LAST OFFPAGE TRUE
J 2
(-8625 4025);
DISPLAY 0.872340 (-8625 4025);
PAINT GREEN (-8625 4025);
DISPLAY INVISIBLE (-8625 4025);
FORCEPROP 1 LAST COMMENT_BODY TRUE
J 2
(-8275 4050);
DISPLAY 0.872340 (-8275 4050);
PAINT GREEN (-8275 4050);
DISPLAY INVISIBLE (-8275 4050);
FORCEPROP 2 LAST PATH I15
J 0
(-8250 4225);
DISPLAY 0.680851 (-8250 4225);
DISPLAY INVISIBLE (-8250 4225);
FORCEADD OFFPAGE..4
R 2
(-8300 4200);
FORCEPROP 2 LAST $XR0 122 
J 0
(-8552 4200);
DISPLAY 0.638298 (-8552 4200);
PAINT MONO (-8552 4200);
FORCEPROP 2 LAST CDS_LIB standard
J 0
(-8300 4200);
DISPLAY INVISIBLE (-8300 4200);
FORCEPROP 1 LAST OFFPAGE TRUE
J 2
(-8625 4075);
DISPLAY 0.872340 (-8625 4075);
PAINT GREEN (-8625 4075);
DISPLAY INVISIBLE (-8625 4075);
FORCEPROP 1 LAST COMMENT_BODY TRUE
J 2
(-8275 4100);
DISPLAY 0.872340 (-8275 4100);
PAINT GREEN (-8275 4100);
DISPLAY INVISIBLE (-8275 4100);
FORCEPROP 2 LAST PATH I16
J 0
(-8250 4275);
DISPLAY 0.680851 (-8250 4275);
DISPLAY INVISIBLE (-8250 4275);
FORCEADD OFFPAGE..2
(-5575 4150);
FORCEPROP 2 LAST $XR0 111 
J 0
(-5386 4150);
DISPLAY 0.638298 (-5386 4150);
PAINT MONO (-5386 4150);
FORCEPROP 2 LAST CDS_LIB standard
J 0
(-5575 4150);
DISPLAY INVISIBLE (-5575 4150);
FORCEPROP 1 LAST OFFPAGE TRUE
J 0
(-5250 4025);
DISPLAY 0.872340 (-5250 4025);
PAINT AQUA (-5250 4025);
DISPLAY INVISIBLE (-5250 4025);
FORCEPROP 1 LAST COMMENT_BODY TRUE
J 0
(-5620 4055);
DISPLAY 0.872340 (-5620 4055);
PAINT GREEN (-5620 4055);
DISPLAY INVISIBLE (-5620 4055);
FORCEPROP 2 LAST PATH I17
J 0
(-5400 4225);
DISPLAY 0.680851 (-5400 4225);
DISPLAY INVISIBLE (-5400 4225);
FORCEADD OFFPAGE..2
(-5575 4200);
FORCEPROP 2 LAST $XR0 111 
J 0
(-5386 4200);
DISPLAY 0.638298 (-5386 4200);
PAINT MONO (-5386 4200);
FORCEPROP 2 LAST CDS_LIB standard
J 0
(-5575 4200);
DISPLAY INVISIBLE (-5575 4200);
FORCEPROP 1 LAST OFFPAGE TRUE
J 0
(-5250 4075);
DISPLAY 0.872340 (-5250 4075);
PAINT AQUA (-5250 4075);
DISPLAY INVISIBLE (-5250 4075);
FORCEPROP 1 LAST COMMENT_BODY TRUE
J 0
(-5620 4105);
DISPLAY 0.872340 (-5620 4105);
PAINT GREEN (-5620 4105);
DISPLAY INVISIBLE (-5620 4105);
FORCEPROP 2 LAST PATH I18
J 0
(-5400 4275);
DISPLAY 0.680851 (-5400 4275);
DISPLAY INVISIBLE (-5400 4275);
FORCEADD OFFPAGE..2
(-5550 3850);
FORCEPROP 2 LAST $XR0 112 
J 0
(-5361 3850);
DISPLAY 0.638298 (-5361 3850);
PAINT MONO (-5361 3850);
FORCEPROP 2 LAST CDS_LIB standard
J 0
(-5550 3850);
DISPLAY INVISIBLE (-5550 3850);
FORCEPROP 1 LAST OFFPAGE TRUE
J 0
(-5225 3725);
DISPLAY 0.872340 (-5225 3725);
PAINT AQUA (-5225 3725);
DISPLAY INVISIBLE (-5225 3725);
FORCEPROP 1 LAST COMMENT_BODY TRUE
J 0
(-5595 3755);
DISPLAY 0.872340 (-5595 3755);
PAINT GREEN (-5595 3755);
DISPLAY INVISIBLE (-5595 3755);
FORCEPROP 2 LAST PATH I19
J 0
(-5375 3925);
DISPLAY 0.680851 (-5375 3925);
DISPLAY INVISIBLE (-5375 3925);
FORCEADD Q_RES..1
(-7125 4925);
FORCEPROP 1 LAST LOCATION R6155
J 0
(-7400 4925);
DISPLAY 0.808511 (-7400 4925);
FORCEPROP 0 LAST $SEC 1
J 0
(-6775 4975);
DISPLAY 0.680851 (-6775 4975);
PAINT MONO (-6775 4975);
DISPLAY INVISIBLE (-6775 4975);
FORCEPROP 0 LAST CDS_SEC 1
J 0
(-6775 4975);
DISPLAY 0.680851 (-6775 4975);
DISPLAY INVISIBLE (-6775 4975);
FORCEPROP 1 LASTPIN (-7225 4925) $PN 1
J 0
(-7213 4937);
DISPLAY 0.787234 (-7213 4937);
PAINT MONO (-7213 4937);
FORCEPROP 1 LASTPIN (-7025 4925) $PN 2
J 0
(-7063 4937);
DISPLAY 0.787234 (-7063 4937);
PAINT MONO (-7063 4937);
FORCEPROP 1 LAST PACK_TYPE 0201LF
J 0
(-6650 4925);
DISPLAY 0.808511 (-6650 4925);
FORCEPROP 1 LAST VALUE 0
J 2
(-6925 4925);
DISPLAY 0.808511 (-6925 4925);
FORCEPROP 1 LAST MATERIAL CHIP
J 0
(-6850 4925);
DISPLAY 0.808511 (-6850 4925);
FORCEPROP 2 LAST ROOM PCIE REDRIVER BOM2
J 0
(-7375 4850);
DISPLAY 0.680851 (-7375 4850);
PAINT RED (-7375 4850);
FORCEPROP 1 LAST TOLERANCE 5%
J 0
(-7300 5050);
DISPLAY 0.978723 (-7300 5050);
DISPLAY INVISIBLE (-7300 5050);
FORCEPROP 1 LAST WATTAGE 1/20W
J 2
(-6850 5050);
DISPLAY 0.978723 (-6850 5050);
DISPLAY INVISIBLE (-6850 5050);
FORCEPROP 2 LAST CDS_LIB pure_quanta
J 0
(-7125 4925);
DISPLAY INVISIBLE (-7125 4925);
FORCEPROP 1 LAST PATH I2
J 0
(-7175 5075);
DISPLAY 0.978723 (-7175 5075);
PAINT WHITE (-7175 5075);
DISPLAY INVISIBLE (-7175 5075);
FORCEPROP 1 LAST PART_NUMBER CS00001JE10
J 0
(-7350 5100);
DISPLAY 0.978723 (-7350 5100);
DISPLAY INVISIBLE (-7350 5100);
FORCEADD OFFPAGE..2
(-5550 3800);
FORCEPROP 2 LAST $XR0 112 
J 0
(-5361 3800);
DISPLAY 0.638298 (-5361 3800);
PAINT MONO (-5361 3800);
FORCEPROP 2 LAST CDS_LIB standard
J 0
(-5550 3800);
DISPLAY INVISIBLE (-5550 3800);
FORCEPROP 1 LAST OFFPAGE TRUE
J 0
(-5225 3675);
DISPLAY 0.872340 (-5225 3675);
PAINT AQUA (-5225 3675);
DISPLAY INVISIBLE (-5225 3675);
FORCEPROP 1 LAST COMMENT_BODY TRUE
J 0
(-5595 3705);
DISPLAY 0.872340 (-5595 3705);
PAINT GREEN (-5595 3705);
DISPLAY INVISIBLE (-5595 3705);
FORCEPROP 2 LAST PATH I20
J 0
(-5375 3875);
DISPLAY 0.680851 (-5375 3875);
DISPLAY INVISIBLE (-5375 3875);
FORCEADD Q_RES..1
(-7225 4200);
FORCEPROP 1 LAST LOCATION R6156
J 0
(-7475 4200);
DISPLAY 0.787234 (-7475 4200);
FORCEPROP 0 LAST $SEC 1
J 0
(-7450 4375);
DISPLAY 0.680851 (-7450 4375);
PAINT MONO (-7450 4375);
DISPLAY INVISIBLE (-7450 4375);
FORCEPROP 0 LAST CDS_SEC 1
J 0
(-7450 4375);
DISPLAY 0.680851 (-7450 4375);
DISPLAY INVISIBLE (-7450 4375);
FORCEPROP 1 LASTPIN (-7325 4200) $PN 1
J 0
(-7313 4212);
DISPLAY 0.787234 (-7313 4212);
PAINT MONO (-7313 4212);
FORCEPROP 1 LASTPIN (-7125 4200) $PN 2
J 0
(-7163 4212);
DISPLAY 0.787234 (-7163 4212);
PAINT MONO (-7163 4212);
FORCEPROP 2 LAST ROOM PCIE REDRIVER BOM1
J 0
(-7425 4250);
DISPLAY 0.680851 (-7425 4250);
PAINT RED (-7425 4250);
FORCEPROP 1 LAST MATERIAL CHIP
J 0
(-6850 4200);
DISPLAY 0.808511 (-6850 4200);
FORCEPROP 1 LAST PACK_TYPE 0201LF
J 0
(-6650 4200);
DISPLAY 0.808511 (-6650 4200);
FORCEPROP 1 LAST VALUE 0
J 2
(-6975 4200);
DISPLAY 0.808511 (-6975 4200);
FORCEPROP 1 LAST TOLERANCE 5%
J 0
(-7425 4375);
DISPLAY 0.808511 (-7425 4375);
FORCEPROP 1 LAST WATTAGE 1/20W
J 2
(-6975 4375);
DISPLAY 0.808511 (-6975 4375);
FORCEPROP 2 LAST CDS_LIB pure_quanta
J 0
(-7225 4200);
DISPLAY INVISIBLE (-7225 4200);
FORCEPROP 1 LAST PATH I21
J 0
(-7275 4350);
DISPLAY 0.978723 (-7275 4350);
PAINT WHITE (-7275 4350);
DISPLAY INVISIBLE (-7275 4350);
FORCEPROP 1 LAST PART_NUMBER CS00001JE10
J 0
(-7425 4425);
DISPLAY 0.808511 (-7425 4425);
DISPLAY INVISIBLE (-7425 4425);
FORCEADD Q_RES..1
(-7225 4150);
FORCEPROP 1 LAST LOCATION R6157
J 0
(-7475 4150);
DISPLAY 0.787234 (-7475 4150);
FORCEPROP 0 LAST $SEC 1
J 0
(-6825 4200);
DISPLAY 0.680851 (-6825 4200);
PAINT MONO (-6825 4200);
DISPLAY INVISIBLE (-6825 4200);
FORCEPROP 0 LAST CDS_SEC 1
J 0
(-6825 4200);
DISPLAY 0.680851 (-6825 4200);
DISPLAY INVISIBLE (-6825 4200);
FORCEPROP 1 LASTPIN (-7325 4150) $PN 1
J 0
(-7313 4162);
DISPLAY 0.787234 (-7313 4162);
PAINT MONO (-7313 4162);
FORCEPROP 1 LASTPIN (-7125 4150) $PN 2
J 0
(-7163 4162);
DISPLAY 0.787234 (-7163 4162);
PAINT MONO (-7163 4162);
FORCEPROP 1 LAST PACK_TYPE 0201LF
J 0
(-6650 4150);
DISPLAY 0.808511 (-6650 4150);
FORCEPROP 1 LAST MATERIAL CHIP
J 0
(-6850 4150);
DISPLAY 0.808511 (-6850 4150);
FORCEPROP 1 LAST VALUE 0
J 2
(-6975 4150);
DISPLAY 0.808511 (-6975 4150);
FORCEPROP 2 LAST ROOM PCIE REDRIVER BOM1
J 0
(-7450 4075);
DISPLAY 0.680851 (-7450 4075);
PAINT RED (-7450 4075);
FORCEPROP 2 LAST CDS_LIB pure_quanta
J 0
(-7225 4150);
DISPLAY INVISIBLE (-7225 4150);
FORCEPROP 1 LAST WATTAGE 1/20W
J 2
(-6950 4275);
DISPLAY 0.978723 (-6950 4275);
DISPLAY INVISIBLE (-6950 4275);
FORCEPROP 1 LAST TOLERANCE 5%
J 0
(-7400 4275);
DISPLAY 0.978723 (-7400 4275);
DISPLAY INVISIBLE (-7400 4275);
FORCEPROP 1 LAST PATH I22
J 0
(-7275 4300);
DISPLAY 0.978723 (-7275 4300);
PAINT WHITE (-7275 4300);
DISPLAY INVISIBLE (-7275 4300);
FORCEPROP 1 LAST PART_NUMBER CS00001JE10
J 0
(-7450 4325);
DISPLAY 0.978723 (-7450 4325);
DISPLAY INVISIBLE (-7450 4325);
FORCEADD Q_RES..1
(-7200 3800);
FORCEPROP 1 LAST LOCATION R6159
J 0
(-7450 3800);
DISPLAY 0.787234 (-7450 3800);
FORCEPROP 0 LAST $SEC 1
J 0
(-6850 3850);
DISPLAY 0.680851 (-6850 3850);
PAINT MONO (-6850 3850);
DISPLAY INVISIBLE (-6850 3850);
FORCEPROP 0 LAST CDS_SEC 1
J 0
(-6850 3850);
DISPLAY 0.680851 (-6850 3850);
DISPLAY INVISIBLE (-6850 3850);
FORCEPROP 1 LASTPIN (-7300 3800) $PN 1
J 0
(-7288 3812);
DISPLAY 0.787234 (-7288 3812);
PAINT MONO (-7288 3812);
FORCEPROP 1 LASTPIN (-7100 3800) $PN 2
J 0
(-7138 3812);
DISPLAY 0.787234 (-7138 3812);
PAINT MONO (-7138 3812);
FORCEPROP 2 LAST ROOM PCIE REDRIVER BOM2
J 0
(-7450 3725);
DISPLAY 0.680851 (-7450 3725);
PAINT RED (-7450 3725);
FORCEPROP 1 LAST PACK_TYPE 0201LF
J 0
(-6675 3800);
DISPLAY 0.808511 (-6675 3800);
FORCEPROP 1 LAST VALUE 0
J 2
(-6975 3800);
DISPLAY 0.808511 (-6975 3800);
FORCEPROP 1 LAST MATERIAL CHIP
J 0
(-6875 3800);
DISPLAY 0.808511 (-6875 3800);
FORCEPROP 1 LAST WATTAGE 1/20W
J 2
(-6925 3925);
DISPLAY 0.978723 (-6925 3925);
DISPLAY INVISIBLE (-6925 3925);
FORCEPROP 1 LAST TOLERANCE 5%
J 0
(-7375 3925);
DISPLAY 0.978723 (-7375 3925);
DISPLAY INVISIBLE (-7375 3925);
FORCEPROP 2 LAST CDS_LIB pure_quanta
J 0
(-7200 3800);
DISPLAY INVISIBLE (-7200 3800);
FORCEPROP 1 LAST PATH I23
J 0
(-7250 3950);
DISPLAY 0.978723 (-7250 3950);
PAINT WHITE (-7250 3950);
DISPLAY INVISIBLE (-7250 3950);
FORCEPROP 1 LAST PART_NUMBER CS00001JE10
J 0
(-7425 3975);
DISPLAY 0.978723 (-7425 3975);
DISPLAY INVISIBLE (-7425 3975);
FORCEADD Q_RES..1
(-7200 3850);
FORCEPROP 1 LAST LOCATION R6158
J 0
(-7450 3850);
DISPLAY 0.787234 (-7450 3850);
FORCEPROP 0 LAST $SEC 1
J 0
(-6850 3900);
DISPLAY 0.680851 (-6850 3900);
PAINT MONO (-6850 3900);
DISPLAY INVISIBLE (-6850 3900);
FORCEPROP 0 LAST CDS_SEC 1
J 0
(-6850 3900);
DISPLAY 0.680851 (-6850 3900);
DISPLAY INVISIBLE (-6850 3900);
FORCEPROP 1 LASTPIN (-7300 3850) $PN 1
J 0
(-7288 3862);
DISPLAY 0.787234 (-7288 3862);
PAINT MONO (-7288 3862);
FORCEPROP 1 LASTPIN (-7100 3850) $PN 2
J 0
(-7138 3862);
DISPLAY 0.787234 (-7138 3862);
PAINT MONO (-7138 3862);
FORCEPROP 1 LAST MATERIAL CHIP
J 0
(-6875 3850);
DISPLAY 0.808511 (-6875 3850);
FORCEPROP 2 LAST ROOM PCIE REDRIVER BOM2
J 0
(-7450 3925);
DISPLAY 0.680851 (-7450 3925);
PAINT RED (-7450 3925);
FORCEPROP 1 LAST VALUE 0
J 2
(-6975 3850);
DISPLAY 0.808511 (-6975 3850);
FORCEPROP 1 LAST PACK_TYPE 0201LF
J 0
(-6675 3850);
DISPLAY 0.808511 (-6675 3850);
FORCEPROP 1 LAST WATTAGE 1/20W
J 2
(-6925 3975);
DISPLAY 0.978723 (-6925 3975);
DISPLAY INVISIBLE (-6925 3975);
FORCEPROP 1 LAST TOLERANCE 5%
J 0
(-7375 3975);
DISPLAY 0.978723 (-7375 3975);
DISPLAY INVISIBLE (-7375 3975);
FORCEPROP 2 LAST CDS_LIB pure_quanta
J 0
(-7200 3850);
DISPLAY INVISIBLE (-7200 3850);
FORCEPROP 1 LAST PATH I24
J 0
(-7250 4000);
DISPLAY 0.978723 (-7250 4000);
PAINT WHITE (-7250 4000);
DISPLAY INVISIBLE (-7250 4000);
FORCEPROP 1 LAST PART_NUMBER CS00001JE10
J 0
(-7425 4025);
DISPLAY 0.978723 (-7425 4025);
DISPLAY INVISIBLE (-7425 4025);
FORCEADD OFFPAGE..2
(-1050 5200);
FORCEPROP 2 LAST $XR0 122 
J 0
(-861 5200);
DISPLAY 0.638298 (-861 5200);
PAINT MONO (-861 5200);
FORCEPROP 2 LAST CDS_LIB standard
J 0
(-1050 5200);
DISPLAY INVISIBLE (-1050 5200);
FORCEPROP 1 LAST OFFPAGE TRUE
J 0
(-725 5075);
DISPLAY 0.872340 (-725 5075);
PAINT AQUA (-725 5075);
DISPLAY INVISIBLE (-725 5075);
FORCEPROP 1 LAST COMMENT_BODY TRUE
J 0
(-1095 5105);
DISPLAY 0.872340 (-1095 5105);
PAINT GREEN (-1095 5105);
DISPLAY INVISIBLE (-1095 5105);
FORCEPROP 2 LAST PATH I25
J 0
(-875 5275);
DISPLAY 0.680851 (-875 5275);
DISPLAY INVISIBLE (-875 5275);
FORCEADD OFFPAGE..2
(-1050 5250);
FORCEPROP 2 LAST $XR0 122 
J 0
(-861 5250);
DISPLAY 0.638298 (-861 5250);
PAINT MONO (-861 5250);
FORCEPROP 2 LAST CDS_LIB standard
J 0
(-1050 5250);
DISPLAY INVISIBLE (-1050 5250);
FORCEPROP 1 LAST OFFPAGE TRUE
J 0
(-725 5125);
DISPLAY 0.872340 (-725 5125);
PAINT AQUA (-725 5125);
DISPLAY INVISIBLE (-725 5125);
FORCEPROP 1 LAST COMMENT_BODY TRUE
J 0
(-1095 5155);
DISPLAY 0.872340 (-1095 5155);
PAINT GREEN (-1095 5155);
DISPLAY INVISIBLE (-1095 5155);
FORCEPROP 2 LAST PATH I26
J 0
(-875 5325);
DISPLAY 0.680851 (-875 5325);
DISPLAY INVISIBLE (-875 5325);
FORCEADD Q_RES..1
(-7150 5275);
FORCEPROP 1 LAST LOCATION R6153
J 0
(-7425 5275);
DISPLAY 0.808511 (-7425 5275);
FORCEPROP 0 LAST $SEC 1
J 0
(-6750 5325);
DISPLAY 0.680851 (-6750 5325);
PAINT MONO (-6750 5325);
DISPLAY INVISIBLE (-6750 5325);
FORCEPROP 0 LAST CDS_SEC 1
J 0
(-6750 5325);
DISPLAY 0.680851 (-6750 5325);
DISPLAY INVISIBLE (-6750 5325);
FORCEPROP 1 LASTPIN (-7250 5275) $PN 1
J 0
(-7238 5287);
DISPLAY 0.787234 (-7238 5287);
PAINT MONO (-7238 5287);
FORCEPROP 1 LASTPIN (-7050 5275) $PN 2
J 0
(-7088 5287);
DISPLAY 0.787234 (-7088 5287);
PAINT MONO (-7088 5287);
FORCEPROP 2 LAST ROOM PCIE REDRIVER BOM1
J 0
(-7375 5200);
DISPLAY 0.680851 (-7375 5200);
PAINT RED (-7375 5200);
FORCEPROP 1 LAST MATERIAL CHIP
J 0
(-6850 5275);
DISPLAY 0.808511 (-6850 5275);
FORCEPROP 1 LAST VALUE 0
J 2
(-6925 5275);
DISPLAY 0.808511 (-6925 5275);
FORCEPROP 1 LAST PACK_TYPE 0201LF
J 0
(-6625 5275);
DISPLAY 0.808511 (-6625 5275);
FORCEPROP 2 LAST CDS_LIB pure_quanta
J 0
(-7150 5275);
DISPLAY INVISIBLE (-7150 5275);
FORCEPROP 1 LAST TOLERANCE 5%
J 0
(-7325 5400);
DISPLAY 0.978723 (-7325 5400);
DISPLAY INVISIBLE (-7325 5400);
FORCEPROP 1 LAST WATTAGE 1/20W
J 2
(-6875 5400);
DISPLAY 0.978723 (-6875 5400);
DISPLAY INVISIBLE (-6875 5400);
FORCEPROP 1 LAST PATH I3
J 0
(-7200 5425);
DISPLAY 0.978723 (-7200 5425);
PAINT WHITE (-7200 5425);
DISPLAY INVISIBLE (-7200 5425);
FORCEPROP 1 LAST PART_NUMBER CS00001JE10
J 0
(-7375 5450);
DISPLAY 0.978723 (-7375 5450);
DISPLAY INVISIBLE (-7375 5450);
FORCEADD OFFPAGE..4
R 2
(-3775 5200);
FORCEPROP 2 LAST $XR0 111 
J 0
(-4027 5200);
DISPLAY 0.638298 (-4027 5200);
PAINT MONO (-4027 5200);
FORCEPROP 2 LAST CDS_LIB standard
J 0
(-3775 5200);
DISPLAY INVISIBLE (-3775 5200);
FORCEPROP 1 LAST OFFPAGE TRUE
J 2
(-4100 5075);
DISPLAY 0.872340 (-4100 5075);
PAINT GREEN (-4100 5075);
DISPLAY INVISIBLE (-4100 5075);
FORCEPROP 1 LAST COMMENT_BODY TRUE
J 2
(-3750 5100);
DISPLAY 0.872340 (-3750 5100);
PAINT GREEN (-3750 5100);
DISPLAY INVISIBLE (-3750 5100);
FORCEPROP 2 LAST PATH I33
J 0
(-3725 5275);
DISPLAY 0.680851 (-3725 5275);
DISPLAY INVISIBLE (-3725 5275);
FORCEADD OFFPAGE..4
R 2
(-3775 5250);
FORCEPROP 2 LAST $XR0 111 
J 0
(-4027 5250);
DISPLAY 0.638298 (-4027 5250);
PAINT MONO (-4027 5250);
FORCEPROP 2 LAST CDS_LIB standard
J 0
(-3775 5250);
DISPLAY INVISIBLE (-3775 5250);
FORCEPROP 1 LAST OFFPAGE TRUE
J 2
(-4100 5125);
DISPLAY 0.872340 (-4100 5125);
PAINT GREEN (-4100 5125);
DISPLAY INVISIBLE (-4100 5125);
FORCEPROP 1 LAST COMMENT_BODY TRUE
J 2
(-3750 5150);
DISPLAY 0.872340 (-3750 5150);
PAINT GREEN (-3750 5150);
DISPLAY INVISIBLE (-3750 5150);
FORCEPROP 2 LAST PATH I34
J 0
(-3725 5325);
DISPLAY 0.680851 (-3725 5325);
DISPLAY INVISIBLE (-3725 5325);
FORCEADD Q_CAP..2
(-2650 4850);
FORCEPROP 1 LAST LOCATION C6006
J 1
(-2850 4850);
DISPLAY 0.510638 (-2850 4850);
FORCEPROP 0 LAST $SEC 1
J 0
(-2625 5025);
DISPLAY 0.680851 (-2625 5025);
PAINT MONO (-2625 5025);
DISPLAY INVISIBLE (-2625 5025);
FORCEPROP 0 LAST CDS_SEC 1
J 0
(-2625 5025);
DISPLAY 0.680851 (-2625 5025);
DISPLAY INVISIBLE (-2625 5025);
FORCEPROP 1 LASTPIN (-2750 4850) $PN 1
J 0
(-2760 4865);
DISPLAY 0.787234 (-2760 4865);
PAINT MONO (-2760 4865);
FORCEPROP 1 LASTPIN (-2550 4850) $PN 2
J 0
(-2565 4865);
DISPLAY 0.787234 (-2565 4865);
PAINT MONO (-2565 4865);
FORCEPROP 1 LAST VOLTAGE 25V
J 0
(-2625 5025);
DISPLAY 0.638298 (-2625 5025);
FORCEPROP 1 LAST VALUE 0.1UF
J 2
(-2625 5025);
DISPLAY 0.638298 (-2625 5025);
FORCEPROP 2 LAST ROOM PCIE REDRIVER BOM2
J 0
(-2875 4775);
DISPLAY 0.680851 (-2875 4775);
PAINT RED (-2875 4775);
FORCEPROP 1 LAST TOLERANCE 10%
J 2
(-2525 5000);
DISPLAY 0.638298 (-2525 5000);
DISPLAY INVISIBLE (-2525 5000);
FORCEPROP 1 LAST PACK_TYPE 0402
J 1
(-2700 5000);
DISPLAY 0.638298 (-2700 5000);
DISPLAY INVISIBLE (-2700 5000);
FORCEPROP 1 LAST MATERIAL X7R
J 0
(-2525 5050);
DISPLAY 0.638298 (-2525 5050);
DISPLAY INVISIBLE (-2525 5050);
FORCEPROP 2 LAST CDS_LIB pure_quanta
J 0
(-2650 4850);
DISPLAY INVISIBLE (-2650 4850);
FORCEPROP 1 LAST PATH I35
J 0
(-2650 5050);
DISPLAY 0.978723 (-2650 5050);
PAINT WHITE (-2650 5050);
DISPLAY INVISIBLE (-2650 5050);
FORCEPROP 1 LAST PART_NUMBER CH4104K1B00
J 1
(-2650 5100);
DISPLAY 0.510638 (-2650 5100);
DISPLAY INVISIBLE (-2650 5100);
FORCEADD Q_CAP..2
(-2650 4900);
FORCEPROP 1 LAST LOCATION C6005
J 1
(-2850 4900);
DISPLAY 0.510638 (-2850 4900);
FORCEPROP 0 LAST $SEC 1
J 0
(-2775 4925);
DISPLAY 0.680851 (-2775 4925);
PAINT MONO (-2775 4925);
DISPLAY INVISIBLE (-2775 4925);
FORCEPROP 0 LAST CDS_SEC 1
J 0
(-2775 4925);
DISPLAY 0.680851 (-2775 4925);
DISPLAY INVISIBLE (-2775 4925);
FORCEPROP 1 LASTPIN (-2750 4900) $PN 1
J 0
(-2760 4915);
DISPLAY 0.787234 (-2760 4915);
PAINT MONO (-2760 4915);
FORCEPROP 1 LASTPIN (-2550 4900) $PN 2
J 0
(-2565 4915);
DISPLAY 0.787234 (-2565 4915);
PAINT MONO (-2565 4915);
FORCEPROP 2 LAST ROOM PCIE REDRIVER BOM2
J 0
(-2875 4975);
DISPLAY 0.680851 (-2875 4975);
PAINT RED (-2875 4975);
FORCEPROP 1 LAST VOLTAGE 25V
J 0
(-2625 4700);
DISPLAY 0.638298 (-2625 4700);
DISPLAY INVISIBLE (-2625 4700);
FORCEPROP 1 LAST VALUE 0.1UF
J 2
(-2625 4700);
DISPLAY 0.638298 (-2625 4700);
DISPLAY INVISIBLE (-2625 4700);
FORCEPROP 1 LAST TOLERANCE 10%
J 2
(-2625 4650);
DISPLAY 0.638298 (-2625 4650);
DISPLAY INVISIBLE (-2625 4650);
FORCEPROP 1 LAST PACK_TYPE 0402
J 1
(-2625 4600);
DISPLAY 0.638298 (-2625 4600);
DISPLAY INVISIBLE (-2625 4600);
FORCEPROP 1 LAST MATERIAL X7R
J 0
(-2625 4650);
DISPLAY 0.638298 (-2625 4650);
DISPLAY INVISIBLE (-2625 4650);
FORCEPROP 2 LAST CDS_LIB pure_quanta
J 0
(-2650 4900);
DISPLAY INVISIBLE (-2650 4900);
FORCEPROP 1 LAST PATH I36
J 0
(-2650 5100);
DISPLAY 0.978723 (-2650 5100);
PAINT WHITE (-2650 5100);
DISPLAY INVISIBLE (-2650 5100);
FORCEPROP 1 LAST PART_NUMBER CH4104K1B00
J 1
(-2625 4575);
DISPLAY 0.510638 (-2625 4575);
DISPLAY INVISIBLE (-2625 4575);
FORCEADD OFFPAGE..4
R 2
(-3775 4900);
FORCEPROP 2 LAST $XR0 112 
J 0
(-4027 4900);
DISPLAY 0.638298 (-4027 4900);
PAINT MONO (-4027 4900);
FORCEPROP 2 LAST CDS_LIB standard
J 0
(-3775 4900);
DISPLAY INVISIBLE (-3775 4900);
FORCEPROP 1 LAST OFFPAGE TRUE
J 2
(-4100 4775);
DISPLAY 0.872340 (-4100 4775);
PAINT GREEN (-4100 4775);
DISPLAY INVISIBLE (-4100 4775);
FORCEPROP 1 LAST COMMENT_BODY TRUE
J 2
(-3750 4800);
DISPLAY 0.872340 (-3750 4800);
PAINT GREEN (-3750 4800);
DISPLAY INVISIBLE (-3750 4800);
FORCEPROP 2 LAST PATH I37
J 0
(-3725 4975);
DISPLAY 0.680851 (-3725 4975);
DISPLAY INVISIBLE (-3725 4975);
FORCEADD OFFPAGE..4
R 2
(-3775 4850);
FORCEPROP 2 LAST $XR0 112 
J 0
(-4027 4850);
DISPLAY 0.638298 (-4027 4850);
PAINT MONO (-4027 4850);
FORCEPROP 2 LAST CDS_LIB standard
J 0
(-3775 4850);
DISPLAY INVISIBLE (-3775 4850);
FORCEPROP 1 LAST OFFPAGE TRUE
J 2
(-4100 4725);
DISPLAY 0.872340 (-4100 4725);
PAINT GREEN (-4100 4725);
DISPLAY INVISIBLE (-4100 4725);
FORCEPROP 1 LAST COMMENT_BODY TRUE
J 2
(-3750 4750);
DISPLAY 0.872340 (-3750 4750);
PAINT GREEN (-3750 4750);
DISPLAY INVISIBLE (-3750 4750);
FORCEPROP 2 LAST PATH I38
J 0
(-3725 4925);
DISPLAY 0.680851 (-3725 4925);
DISPLAY INVISIBLE (-3725 4925);
FORCEADD OFFPAGE..2
(-1025 4275);
FORCEPROP 2 LAST $XR0 150 
J 0
(-836 4275);
DISPLAY 0.638298 (-836 4275);
PAINT MONO (-836 4275);
FORCEPROP 2 LAST CDS_LIB standard
J 0
(-1025 4275);
DISPLAY INVISIBLE (-1025 4275);
FORCEPROP 1 LAST OFFPAGE TRUE
J 0
(-700 4150);
DISPLAY 0.872340 (-700 4150);
PAINT AQUA (-700 4150);
DISPLAY INVISIBLE (-700 4150);
FORCEPROP 1 LAST COMMENT_BODY TRUE
J 0
(-1070 4180);
DISPLAY 0.872340 (-1070 4180);
PAINT GREEN (-1070 4180);
DISPLAY INVISIBLE (-1070 4180);
FORCEPROP 2 LAST PATH I39
J 0
(-850 4350);
DISPLAY 0.680851 (-850 4350);
DISPLAY INVISIBLE (-850 4350);
FORCEADD OFFPAGE..2
(-5475 4975);
FORCEPROP 2 LAST $XR0 112 
J 0
(-5286 4975);
DISPLAY 0.638298 (-5286 4975);
PAINT MONO (-5286 4975);
FORCEPROP 2 LAST CDS_LIB standard
J 0
(-5475 4975);
DISPLAY INVISIBLE (-5475 4975);
FORCEPROP 1 LAST OFFPAGE TRUE
J 0
(-5150 4850);
DISPLAY 0.872340 (-5150 4850);
PAINT AQUA (-5150 4850);
DISPLAY INVISIBLE (-5150 4850);
FORCEPROP 1 LAST COMMENT_BODY TRUE
J 0
(-5520 4880);
DISPLAY 0.872340 (-5520 4880);
PAINT GREEN (-5520 4880);
DISPLAY INVISIBLE (-5520 4880);
FORCEPROP 2 LAST PATH I4
J 0
(-5300 5050);
DISPLAY 0.680851 (-5300 5050);
DISPLAY INVISIBLE (-5300 5050);
FORCEADD OFFPAGE..2
(-1025 4225);
FORCEPROP 2 LAST $XR0 150 
J 0
(-836 4225);
DISPLAY 0.638298 (-836 4225);
PAINT MONO (-836 4225);
FORCEPROP 2 LAST CDS_LIB standard
J 0
(-1025 4225);
DISPLAY INVISIBLE (-1025 4225);
FORCEPROP 1 LAST OFFPAGE TRUE
J 0
(-700 4100);
DISPLAY 0.872340 (-700 4100);
PAINT AQUA (-700 4100);
DISPLAY INVISIBLE (-700 4100);
FORCEPROP 1 LAST COMMENT_BODY TRUE
J 0
(-1070 4130);
DISPLAY 0.872340 (-1070 4130);
PAINT GREEN (-1070 4130);
DISPLAY INVISIBLE (-1070 4130);
FORCEPROP 2 LAST PATH I40
J 0
(-850 4300);
DISPLAY 0.680851 (-850 4300);
DISPLAY INVISIBLE (-850 4300);
FORCEADD Q_CAP..2
(-2550 3925);
FORCEPROP 1 LAST LOCATION C6007
J 1
(-2700 3925);
DISPLAY 0.638298 (-2700 3925);
FORCEPROP 0 LAST $SEC 1
J 0
(-2700 3975);
DISPLAY 0.680851 (-2700 3975);
PAINT MONO (-2700 3975);
DISPLAY INVISIBLE (-2700 3975);
FORCEPROP 0 LAST CDS_SEC 1
J 0
(-2700 3975);
DISPLAY 0.680851 (-2700 3975);
DISPLAY INVISIBLE (-2700 3975);
FORCEPROP 1 LASTPIN (-2650 3925) $PN 1
J 0
(-2660 3940);
DISPLAY 0.787234 (-2660 3940);
PAINT MONO (-2660 3940);
FORCEPROP 1 LASTPIN (-2450 3925) $PN 2
J 0
(-2465 3940);
DISPLAY 0.787234 (-2465 3940);
PAINT MONO (-2465 3940);
FORCEPROP 2 LAST ROOM PCIE REDRIVER BOM2
J 0
(-2775 4000);
DISPLAY 0.680851 (-2775 4000);
PAINT RED (-2775 4000);
FORCEPROP 2 LAST CDS_LIB pure_quanta
J 0
(-2550 3925);
DISPLAY INVISIBLE (-2550 3925);
FORCEPROP 1 LAST VOLTAGE 25V
J 0
(-2525 3725);
DISPLAY 0.638298 (-2525 3725);
DISPLAY INVISIBLE (-2525 3725);
FORCEPROP 1 LAST VALUE 0.1UF
J 2
(-2525 3725);
DISPLAY 0.638298 (-2525 3725);
DISPLAY INVISIBLE (-2525 3725);
FORCEPROP 1 LAST TOLERANCE 10%
J 2
(-2525 3675);
DISPLAY 0.638298 (-2525 3675);
DISPLAY INVISIBLE (-2525 3675);
FORCEPROP 1 LAST PACK_TYPE 0402
J 1
(-2525 3625);
DISPLAY 0.638298 (-2525 3625);
DISPLAY INVISIBLE (-2525 3625);
FORCEPROP 1 LAST MATERIAL X7R
J 0
(-2525 3675);
DISPLAY 0.638298 (-2525 3675);
DISPLAY INVISIBLE (-2525 3675);
FORCEPROP 1 LAST PATH I43
J 0
(-2550 4125);
DISPLAY 0.978723 (-2550 4125);
PAINT WHITE (-2550 4125);
DISPLAY INVISIBLE (-2550 4125);
FORCEPROP 1 LAST PART_NUMBER CH4104K1B00
J 1
(-2525 3600);
DISPLAY 0.510638 (-2525 3600);
DISPLAY INVISIBLE (-2525 3600);
FORCEADD Q_CAP..2
(-2550 3875);
FORCEPROP 1 LAST LOCATION C6008
J 1
(-2700 3875);
DISPLAY 0.638298 (-2700 3875);
FORCEPROP 0 LAST $SEC 1
J 0
(-2700 3925);
DISPLAY 0.680851 (-2700 3925);
PAINT MONO (-2700 3925);
DISPLAY INVISIBLE (-2700 3925);
FORCEPROP 0 LAST CDS_SEC 1
J 0
(-2700 3925);
DISPLAY 0.680851 (-2700 3925);
DISPLAY INVISIBLE (-2700 3925);
FORCEPROP 1 LASTPIN (-2650 3875) $PN 1
J 0
(-2660 3890);
DISPLAY 0.787234 (-2660 3890);
PAINT MONO (-2660 3890);
FORCEPROP 1 LASTPIN (-2450 3875) $PN 2
J 0
(-2465 3890);
DISPLAY 0.787234 (-2465 3890);
PAINT MONO (-2465 3890);
FORCEPROP 2 LAST ROOM PCIE REDRIVER BOM2
J 0
(-2750 3800);
DISPLAY 0.680851 (-2750 3800);
PAINT RED (-2750 3800);
FORCEPROP 1 LAST VOLTAGE 25V
J 0
(-2525 4000);
DISPLAY 0.638298 (-2525 4000);
DISPLAY INVISIBLE (-2525 4000);
FORCEPROP 1 LAST VALUE 0.1UF
J 2
(-2525 4000);
DISPLAY 0.638298 (-2525 4000);
DISPLAY INVISIBLE (-2525 4000);
FORCEPROP 2 LAST CDS_LIB pure_quanta
J 0
(-2550 3875);
DISPLAY INVISIBLE (-2550 3875);
FORCEPROP 1 LAST TOLERANCE 10%
J 2
(-2425 4025);
DISPLAY 0.638298 (-2425 4025);
DISPLAY INVISIBLE (-2425 4025);
FORCEPROP 1 LAST PACK_TYPE 0402
J 1
(-2600 4025);
DISPLAY 0.638298 (-2600 4025);
DISPLAY INVISIBLE (-2600 4025);
FORCEPROP 1 LAST MATERIAL X7R
J 0
(-2425 4075);
DISPLAY 0.638298 (-2425 4075);
DISPLAY INVISIBLE (-2425 4075);
FORCEPROP 1 LAST PATH I44
J 0
(-2550 4075);
DISPLAY 0.978723 (-2550 4075);
PAINT WHITE (-2550 4075);
DISPLAY INVISIBLE (-2550 4075);
FORCEPROP 1 LAST PART_NUMBER CH4104K1B00
J 1
(-2550 4125);
DISPLAY 0.510638 (-2550 4125);
DISPLAY INVISIBLE (-2550 4125);
FORCEADD OFFPAGE..4
R 2
(-3750 4275);
FORCEPROP 2 LAST $XR0 111 
J 0
(-4032 4275);
DISPLAY 0.638298 (-4032 4275);
PAINT MONO (-4032 4275);
FORCEPROP 2 LAST CDS_LIB standard
J 0
(-3750 4275);
DISPLAY INVISIBLE (-3750 4275);
FORCEPROP 1 LAST OFFPAGE TRUE
J 2
(-4075 4150);
DISPLAY 0.872340 (-4075 4150);
PAINT GREEN (-4075 4150);
DISPLAY INVISIBLE (-4075 4150);
FORCEPROP 1 LAST COMMENT_BODY TRUE
J 2
(-3725 4175);
DISPLAY 0.872340 (-3725 4175);
PAINT GREEN (-3725 4175);
DISPLAY INVISIBLE (-3725 4175);
FORCEPROP 2 LAST PATH I45
J 0
(-3700 4350);
DISPLAY 0.680851 (-3700 4350);
DISPLAY INVISIBLE (-3700 4350);
FORCEADD OFFPAGE..4
R 2
(-3750 4225);
FORCEPROP 2 LAST $XR0 111 
J 0
(-4032 4225);
DISPLAY 0.638298 (-4032 4225);
PAINT MONO (-4032 4225);
FORCEPROP 2 LAST CDS_LIB standard
J 0
(-3750 4225);
DISPLAY INVISIBLE (-3750 4225);
FORCEPROP 1 LAST OFFPAGE TRUE
J 2
(-4075 4100);
DISPLAY 0.872340 (-4075 4100);
PAINT GREEN (-4075 4100);
DISPLAY INVISIBLE (-4075 4100);
FORCEPROP 1 LAST COMMENT_BODY TRUE
J 2
(-3725 4125);
DISPLAY 0.872340 (-3725 4125);
PAINT GREEN (-3725 4125);
DISPLAY INVISIBLE (-3725 4125);
FORCEPROP 2 LAST PATH I46
J 0
(-3700 4300);
DISPLAY 0.680851 (-3700 4300);
DISPLAY INVISIBLE (-3700 4300);
FORCEADD OFFPAGE..4
R 2
(-3750 3875);
FORCEPROP 2 LAST $XR0 112 
J 0
(-4032 3875);
DISPLAY 0.638298 (-4032 3875);
PAINT MONO (-4032 3875);
FORCEPROP 2 LAST CDS_LIB standard
J 0
(-3750 3875);
DISPLAY INVISIBLE (-3750 3875);
FORCEPROP 1 LAST OFFPAGE TRUE
J 2
(-4075 3750);
DISPLAY 0.872340 (-4075 3750);
PAINT GREEN (-4075 3750);
DISPLAY INVISIBLE (-4075 3750);
FORCEPROP 1 LAST COMMENT_BODY TRUE
J 2
(-3725 3775);
DISPLAY 0.872340 (-3725 3775);
PAINT GREEN (-3725 3775);
DISPLAY INVISIBLE (-3725 3775);
FORCEPROP 2 LAST PATH I47
J 0
(-3700 3950);
DISPLAY 0.680851 (-3700 3950);
DISPLAY INVISIBLE (-3700 3950);
FORCEADD OFFPAGE..4
R 2
(-3750 3925);
FORCEPROP 2 LAST $XR0 112 
J 0
(-4032 3925);
DISPLAY 0.638298 (-4032 3925);
PAINT MONO (-4032 3925);
FORCEPROP 2 LAST CDS_LIB standard
J 0
(-3750 3925);
DISPLAY INVISIBLE (-3750 3925);
FORCEPROP 1 LAST OFFPAGE TRUE
J 2
(-4075 3800);
DISPLAY 0.872340 (-4075 3800);
PAINT GREEN (-4075 3800);
DISPLAY INVISIBLE (-4075 3800);
FORCEPROP 1 LAST COMMENT_BODY TRUE
J 2
(-3725 3825);
DISPLAY 0.872340 (-3725 3825);
PAINT GREEN (-3725 3825);
DISPLAY INVISIBLE (-3725 3825);
FORCEPROP 2 LAST PATH I48
J 0
(-3700 4000);
DISPLAY 0.680851 (-3700 4000);
DISPLAY INVISIBLE (-3700 4000);
FORCEADD OFFPAGE..2
(-5475 4925);
FORCEPROP 2 LAST $XR0 112 
J 0
(-5286 4925);
DISPLAY 0.638298 (-5286 4925);
PAINT MONO (-5286 4925);
FORCEPROP 2 LAST CDS_LIB standard
J 0
(-5475 4925);
DISPLAY INVISIBLE (-5475 4925);
FORCEPROP 1 LAST OFFPAGE TRUE
J 0
(-5150 4800);
DISPLAY 0.872340 (-5150 4800);
PAINT AQUA (-5150 4800);
DISPLAY INVISIBLE (-5150 4800);
FORCEPROP 1 LAST COMMENT_BODY TRUE
J 0
(-5520 4830);
DISPLAY 0.872340 (-5520 4830);
PAINT GREEN (-5520 4830);
DISPLAY INVISIBLE (-5520 4830);
FORCEPROP 2 LAST PATH I5
J 0
(-5300 5000);
DISPLAY 0.680851 (-5300 5000);
DISPLAY INVISIBLE (-5300 5000);
FORCEADD OFFPAGE..2
(-5500 5275);
FORCEPROP 2 LAST $XR0 111 
J 0
(-5311 5275);
DISPLAY 0.638298 (-5311 5275);
PAINT MONO (-5311 5275);
FORCEPROP 2 LAST CDS_LIB standard
J 0
(-5500 5275);
DISPLAY INVISIBLE (-5500 5275);
FORCEPROP 1 LAST OFFPAGE TRUE
J 0
(-5175 5150);
DISPLAY 0.872340 (-5175 5150);
PAINT AQUA (-5175 5150);
DISPLAY INVISIBLE (-5175 5150);
FORCEPROP 1 LAST COMMENT_BODY TRUE
J 0
(-5545 5180);
DISPLAY 0.872340 (-5545 5180);
PAINT GREEN (-5545 5180);
DISPLAY INVISIBLE (-5545 5180);
FORCEPROP 2 LAST PATH I6
J 0
(-5325 5350);
DISPLAY 0.680851 (-5325 5350);
DISPLAY INVISIBLE (-5325 5350);
FORCEADD OFFPAGE..2
(-5500 5325);
FORCEPROP 2 LAST $XR0 111 
J 0
(-5311 5325);
DISPLAY 0.638298 (-5311 5325);
PAINT MONO (-5311 5325);
FORCEPROP 2 LAST CDS_LIB standard
J 0
(-5500 5325);
DISPLAY INVISIBLE (-5500 5325);
FORCEPROP 1 LAST OFFPAGE TRUE
J 0
(-5175 5200);
DISPLAY 0.872340 (-5175 5200);
PAINT AQUA (-5175 5200);
DISPLAY INVISIBLE (-5175 5200);
FORCEPROP 1 LAST COMMENT_BODY TRUE
J 0
(-5545 5230);
DISPLAY 0.872340 (-5545 5230);
PAINT GREEN (-5545 5230);
DISPLAY INVISIBLE (-5545 5230);
FORCEPROP 2 LAST PATH I7
J 0
(-5325 5400);
DISPLAY 0.680851 (-5325 5400);
DISPLAY INVISIBLE (-5325 5400);
FORCEADD Q_RES..1
(-7150 5325);
FORCEPROP 1 LAST LOCATION R6152
J 0
(-7425 5325);
DISPLAY 0.808511 (-7425 5325);
FORCEPROP 0 LAST $SEC 1
J 0
(-7375 5500);
DISPLAY 0.680851 (-7375 5500);
PAINT MONO (-7375 5500);
DISPLAY INVISIBLE (-7375 5500);
FORCEPROP 0 LAST CDS_SEC 1
J 0
(-7375 5500);
DISPLAY 0.680851 (-7375 5500);
DISPLAY INVISIBLE (-7375 5500);
FORCEPROP 1 LASTPIN (-7250 5325) $PN 1
J 0
(-7238 5337);
DISPLAY 0.787234 (-7238 5337);
PAINT MONO (-7238 5337);
FORCEPROP 1 LASTPIN (-7050 5325) $PN 2
J 0
(-7088 5337);
DISPLAY 0.787234 (-7088 5337);
PAINT MONO (-7088 5337);
FORCEPROP 1 LAST TOLERANCE 5%
J 0
(-7325 5525);
DISPLAY 0.808511 (-7325 5525);
FORCEPROP 1 LAST MATERIAL CHIP
J 0
(-6850 5325);
DISPLAY 0.808511 (-6850 5325);
FORCEPROP 1 LAST WATTAGE 1/20W
J 2
(-6875 5525);
DISPLAY 0.808511 (-6875 5525);
FORCEPROP 1 LAST VALUE 0
J 2
(-6925 5325);
DISPLAY 0.808511 (-6925 5325);
FORCEPROP 1 LAST PACK_TYPE 0201LF
J 0
(-6625 5325);
DISPLAY 0.808511 (-6625 5325);
FORCEPROP 2 LAST ROOM PCIE REDRIVER BOM1
J 0
(-7375 5375);
DISPLAY 0.680851 (-7375 5375);
PAINT RED (-7375 5375);
FORCEPROP 2 LAST CDS_LIB pure_quanta
J 0
(-7150 5325);
DISPLAY INVISIBLE (-7150 5325);
FORCEPROP 1 LAST PATH I8
J 0
(-7200 5475);
DISPLAY 0.978723 (-7200 5475);
PAINT WHITE (-7200 5475);
DISPLAY INVISIBLE (-7200 5475);
FORCEPROP 1 LAST PART_NUMBER CS00001JE10
J 0
(-7375 5575);
DISPLAY 0.808511 (-7375 5575);
DISPLAY INVISIBLE (-7375 5575);
FORCEADD OFFPAGE..4
R 2
(-8225 5325);
FORCEPROP 2 LAST $XR0 150 
J 0
(-8477 5325);
DISPLAY 0.638298 (-8477 5325);
PAINT MONO (-8477 5325);
FORCEPROP 2 LAST CDS_LIB standard
J 0
(-8225 5325);
DISPLAY INVISIBLE (-8225 5325);
FORCEPROP 1 LAST OFFPAGE TRUE
J 2
(-8550 5200);
DISPLAY 0.872340 (-8550 5200);
PAINT GREEN (-8550 5200);
DISPLAY INVISIBLE (-8550 5200);
FORCEPROP 1 LAST COMMENT_BODY TRUE
J 2
(-8200 5225);
DISPLAY 0.872340 (-8200 5225);
PAINT GREEN (-8200 5225);
DISPLAY INVISIBLE (-8200 5225);
FORCEPROP 2 LAST PATH I9
J 0
(-8175 5400);
DISPLAY 0.680851 (-8175 5400);
DISPLAY INVISIBLE (-8175 5400);
FORCEADD CAD_NOTE..1
(-7475 6000);
FORCEPROP 0 LAST S1 R6152/R6154 R6153/R6155 CO-LAYOUT
J 0
(-7600 5875);
DISPLAY 0.808511 (-7600 5875);
PAINT WHITE (-7600 5875);
FORCEPROP 2 LAST CDS_LIB pure_quanta_power
J 0
(-7475 6000);
DISPLAY INVISIBLE (-7475 6000);
FORCEPROP 1 LAST COMMENT_BODY TRUE
J 0
(-7450 6100);
DISPLAY 0.978723 (-7450 6100);
DISPLAY INVISIBLE (-7450 6100);
FORCEADD CAD_NOTE..1
(-2725 5750);
FORCEPROP 0 LAST S1 C1870/C6005 C1871/C6006 CO-LAYOUT
J 0
(-3100 5650);
DISPLAY 0.808511 (-3100 5650);
PAINT WHITE (-3100 5650);
FORCEPROP 2 LAST CDS_LIB pure_quanta_power
J 0
(-2725 5750);
DISPLAY INVISIBLE (-2725 5750);
FORCEPROP 1 LAST COMMENT_BODY TRUE
J 0
(-2700 5850);
DISPLAY 0.978723 (-2700 5850);
DISPLAY INVISIBLE (-2700 5850);
FORCEADD CAD_NOTE..1
(-3825 4625);
FORCEPROP 0 LAST S1 C1868/C6007 C1869/C6008 CO-LAYOUT
J 0
(-3950 4500);
DISPLAY 0.808511 (-3950 4500);
PAINT WHITE (-3950 4500);
FORCEPROP 2 LAST CDS_LIB pure_quanta_power
J 0
(-3825 4625);
DISPLAY INVISIBLE (-3825 4625);
FORCEPROP 1 LAST COMMENT_BODY TRUE
J 0
(-3800 4725);
DISPLAY 0.978723 (-3800 4725);
DISPLAY INVISIBLE (-3800 4725);
FORCEADD CAD_NOTE..1
(-7500 4625);
FORCEPROP 0 LAST S1 R6156/R6158 R6157/R6159 CO-LAYOUT
J 0
(-7625 4500);
DISPLAY 0.808511 (-7625 4500);
PAINT WHITE (-7625 4500);
FORCEPROP 2 LAST CDS_LIB pure_quanta_power
J 0
(-7500 4625);
DISPLAY INVISIBLE (-7500 4625);
FORCEPROP 1 LAST COMMENT_BODY TRUE
J 0
(-7475 4725);
DISPLAY 0.978723 (-7475 4725);
DISPLAY INVISIBLE (-7475 4725);
FORCEADD QUANTA_TITLE_BLOCK_C..1
(-100 100);
FORCEPROP 0 LAST CDS_CON_LAST_MODIFIED Thu Sep 14 16:12:44 2023
J 0
(-1985 115);
DISPLAY INVISIBLE (-1985 115);
FORCEPROP 1 LAST CUSTOM_TXT_CDS <CON_LAST_MODIFIED>
J 0
(-1985 115);
DISPLAY 0.978723 (-1985 115);
FORCEPROP 2 LAST CUSTOM_TXT_CDS <XR_PAGE_TITLE>
J 0
(-7990 5350);
DISPLAY 0.638298 (-7990 5350);
PAINT PINK (-7990 5350);
DISPLAY INVISIBLE (-7990 5350);
FORCEPROP 1 LAST CUSTOM_TXT_CDS <NAME_2>
J 0
(-3275 150);
FORCEPROP 1 LAST CUSTOM_TXT_CDS <NAME_1>
J 0
(-3275 275);
FORCEPROP 1 LAST CUSTOM_TXT_CDS <Q_NUMBER>
J 0
(-1503 203);
DISPLAY 1.212766 (-1503 203);
FORCEPROP 1 LAST CUSTOM_TXT_CDS <Q_PROJ>
J 0
(-2482 202);
DISPLAY 1.212766 (-2482 202);
FORCEPROP 1 LAST CUSTOM_TXT_CDS <Q_REV>
J 0
(-284 203);
DISPLAY 1.212766 (-284 203);
FORCEPROP 1 LAST CUSTOM_TXT_CDS <CON_PAGE_NUM> OF <CON_TOTAL_PAGES>
J 0
(-546 118);
DISPLAY 0.978723 (-546 118);
FORCEPROP 1 LAST Q_TITLE BMC-GPU FPGA PCIE RE-DRIVER SELECT
J 0
(-9375 175);
DISPLAY 2.446809 (-9375 175);
PAINT GREEN (-9375 175);
FORCEPROP 2 LAST PAGE_BORDER TRUE
J 0
(-7990 5350);
DISPLAY 0.638298 (-7990 5350);
PAINT PINK (-7990 5350);
DISPLAY INVISIBLE (-7990 5350);
FORCEPROP 1 LAST CDS_LMAN_SYM_OUTLINE -9475,6775,100,-125
J 0
(-100 100);
DISPLAY 0.468085 (-100 100);
PAINT GREEN (-100 100);
DISPLAY INVISIBLE (-100 100);
FORCEPROP 2 LAST CDS_LIB pure_quanta
J 0
(-100 100);
DISPLAY INVISIBLE (-100 100);
FORCEPROP 2 LAST CDS_XR_PAGE_TITLE CR-113 : @T6G_MB_LIB.T6G(SCH_1):PAGE113
J 0
(-7990 5350);
DISPLAY 0.638298 (-7990 5350);
PAINT PINK (-7990 5350);
DISPLAY INVISIBLE (-7990 5350);
FORCEPROP 1 LAST Q_DEPT BU9
J 1
(-3863 149);
DISPLAY 1.957447 (-3863 149);
PAINT GREEN (-3863 149);
DISPLAY INVISIBLE (-3863 149);
FORCEPROP 1 LAST COMMENT_BODY TRUE
J 0
(-88 87);
DISPLAY 0.978723 (-88 87);
PAINT GREEN (-88 87);
DISPLAY INVISIBLE (-88 87);
WIRE 16 2175 (-2925 5375)(-2150 5375);
WIRE 16 2175 (-2925 5375)(-2925 4725);
WIRE 16 2175 (-2150 5375)(-2150 4725);
WIRE 16 2175 (-2925 4725)(-2150 4725);
WIRE 16 -1 (-1100 5250)(-2200 5250);
FORCEPROP 2 LAST SIG_NAME P2E_MB_BMC_TX_BUF_C_DP<0>
J 0
(-2110 5260);
DISPLAY 0.680851 (-2110 5260);
WIRE 16 -1 (-2200 5250)(-2600 5250);
WIRE 16 -1 (-2200 4900)(-2200 5250);
WIRE 16 -1 (-2550 4900)(-2200 4900);
WIRE 16 -1 (-1100 5200)(-2000 5200);
WIRE 16 -1 (-2000 4850)(-2000 5200);
WIRE 16 -1 (-2000 5200)(-2600 5200);
FORCEPROP 2 LAST SIG_NAME P2E_MB_BMC_TX_BUF_C_DN<0>
J 0
(-2110 5210);
DISPLAY 0.680851 (-2110 5210);
WIRE 16 -1 (-2550 4850)(-2000 4850);
WIRE 16 -1 (-2450 3925)(-2175 3925);
WIRE 16 -1 (-2175 3925)(-2175 4275);
WIRE 16 -1 (-1075 4275)(-2175 4275);
FORCEPROP 2 LAST SIG_NAME P2E_MB_BMC_RX_BUF_DP<0>
J 0
(-1860 4285);
DISPLAY 0.680851 (-1860 4285);
WIRE 16 -1 (-2175 4275)(-2450 4275);
WIRE 16 -1 (-2450 3875)(-1975 3875);
WIRE 16 -1 (-1975 3875)(-1975 4225);
WIRE 16 -1 (-1075 4225)(-1975 4225);
FORCEPROP 2 LAST SIG_NAME P2E_MB_BMC_RX_BUF_DN<0>
J 0
(-1835 4235);
DISPLAY 0.680851 (-1835 4235);
WIRE 16 -1 (-1975 4225)(-2450 4225);
WIRE 16 2175 (-2800 4425)(-2100 4425);
WIRE 16 2175 (-2800 4425)(-2800 3725);
WIRE 16 2175 (-2100 4425)(-2100 3725);
WIRE 16 2175 (-2800 3725)(-2100 3725);
WIRE 16 -1 (-3700 4275)(-2650 4275);
FORCEPROP 2 LAST SIG_NAME P2E_MB_BMC_RX_BUF_C_DP<0>
J 0
(-3660 4285);
DISPLAY 0.680851 (-3660 4285);
WIRE 16 -1 (-3700 4225)(-2650 4225);
FORCEPROP 2 LAST SIG_NAME P2E_MB_BMC_RX_BUF_C_DN<0>
J 0
(-3660 4235);
DISPLAY 0.680851 (-3660 4235);
WIRE 16 -1 (-3700 3875)(-2650 3875);
FORCEPROP 2 LAST SIG_NAME P2E_MB_BMC_RX_BUF2_C_DN<0>
J 0
(-3635 3885);
DISPLAY 0.680851 (-3635 3885);
WIRE 16 -1 (-3700 3925)(-2650 3925);
FORCEPROP 2 LAST SIG_NAME P2E_MB_BMC_RX_BUF2_C_DP<0>
J 0
(-3635 3935);
DISPLAY 0.680851 (-3635 3935);
WIRE 16 -1 (-3725 4850)(-2750 4850);
FORCEPROP 2 LAST SIG_NAME P2E_MB_BMC_TX_BUF2_DN<0>
J 0
(-3685 4860);
DISPLAY 0.680851 (-3685 4860);
WIRE 16 -1 (-3725 4900)(-2750 4900);
FORCEPROP 2 LAST SIG_NAME P2E_MB_BMC_TX_BUF2_DP<0>
J 0
(-3685 4910);
DISPLAY 0.680851 (-3685 4910);
WIRE 16 -1 (-3725 5200)(-2800 5200);
FORCEPROP 2 LAST SIG_NAME P2E_MB_BMC_TX_BUF_DN<0>
J 0
(-3685 5210);
DISPLAY 0.680851 (-3685 5210);
WIRE 16 -1 (-3725 5250)(-2800 5250);
FORCEPROP 2 LAST SIG_NAME P2E_MB_BMC_TX_BUF_DP<0>
J 0
(-3685 5260);
DISPLAY 0.680851 (-3685 5260);
WIRE 16 2175 (-7525 4325)(-6425 4325);
WIRE 16 2175 (-7525 4325)(-7525 3700);
WIRE 16 2175 (-6425 4325)(-6425 3700);
WIRE 16 2175 (-7525 3700)(-6425 3700);
WIRE 16 -1 (-5625 4150)(-7125 4150);
FORCEPROP 2 LAST SIG_NAME P2E_MB_BMC_RX_R1_DN<0>
J 0
(-6385 4160);
DISPLAY 0.680851 (-6385 4160);
WIRE 16 -1 (-5600 3800)(-7100 3800);
FORCEPROP 2 LAST SIG_NAME P2E_MB_BMC_RX_R2_DN<0>
J 0
(-6410 3810);
DISPLAY 0.680851 (-6410 3810);
WIRE 16 -1 (-5600 3850)(-7100 3850);
FORCEPROP 2 LAST SIG_NAME P2E_MB_BMC_RX_R2_DP<0>
J 0
(-6410 3860);
DISPLAY 0.680851 (-6410 3860);
WIRE 16 2175 (-7425 5475)(-6400 5475);
WIRE 16 2175 (-7425 5475)(-7425 4800);
WIRE 16 2175 (-6400 5475)(-6400 4800);
WIRE 16 2175 (-7425 4800)(-6400 4800);
WIRE 16 -1 (-5625 4200)(-7125 4200);
FORCEPROP 2 LAST SIG_NAME P2E_MB_BMC_RX_R1_DP<0>
J 0
(-6385 4210);
DISPLAY 0.680851 (-6385 4210);
WIRE 16 -1 (-5525 4925)(-7025 4925);
FORCEPROP 2 LAST SIG_NAME P2E_MB_BMC_TX_C_R2_DN<0>
J 0
(-6385 4935);
DISPLAY 0.680851 (-6385 4935);
WIRE 16 -1 (-5525 4975)(-7025 4975);
FORCEPROP 2 LAST SIG_NAME P2E_MB_BMC_TX_C_R2_DP<0>
J 0
(-6385 4985);
DISPLAY 0.680851 (-6385 4985);
WIRE 16 -1 (-5550 5275)(-7050 5275);
FORCEPROP 2 LAST SIG_NAME P2E_MB_BMC_TX_C_R1_DN<0>
J 0
(-6360 5285);
DISPLAY 0.680851 (-6360 5285);
WIRE 16 -1 (-7325 4150)(-7750 4150);
WIRE 16 -1 (-7750 4150)(-7750 3800);
WIRE 16 -1 (-7750 4150)(-8250 4150);
FORCEPROP 2 LAST SIG_NAME P2E_MB_BMC_RX_DN<0>
J 0
(-8160 4160);
DISPLAY 0.680851 (-8160 4160);
WIRE 16 -1 (-7750 3800)(-7300 3800);
WIRE 16 -1 (-7550 4200)(-7325 4200);
WIRE 16 -1 (-7550 4200)(-7550 3850);
WIRE 16 -1 (-8250 4200)(-7550 4200);
FORCEPROP 2 LAST SIG_NAME P2E_MB_BMC_RX_DP<0>
J 0
(-8160 4210);
DISPLAY 0.680851 (-8160 4210);
WIRE 16 -1 (-7550 3850)(-7300 3850);
WIRE 16 -1 (-5550 5325)(-7050 5325);
FORCEPROP 2 LAST SIG_NAME P2E_MB_BMC_TX_C_R1_DP<0>
J 0
(-6360 5335);
DISPLAY 0.680851 (-6360 5335);
WIRE 16 -1 (-7250 5275)(-7675 5275);
WIRE 16 -1 (-7675 5275)(-8175 5275);
FORCEPROP 2 LAST SIG_NAME P2E_MB_BMC_TX_C_DN<0>
J 0
(-8135 5285);
DISPLAY 0.680851 (-8135 5285);
WIRE 16 -1 (-7675 5275)(-7675 4925);
WIRE 16 -1 (-7675 4925)(-7225 4925);
WIRE 16 -1 (-7475 5325)(-7250 5325);
WIRE 16 -1 (-8175 5325)(-7475 5325);
FORCEPROP 2 LAST SIG_NAME P2E_MB_BMC_TX_C_DP<0>
J 0
(-8135 5335);
DISPLAY 0.680851 (-8135 5335);
WIRE 16 -1 (-7475 5325)(-7475 4975);
WIRE 16 -1 (-7475 4975)(-7225 4975);
DOT 1 (-2175 4275);
DOT 1 (-7550 4200);
DOT 1 (-7475 5325);
DOT 1 (-7675 5275);
DOT 1 (-7750 4150);
DOT 1 (-2000 5200);
DOT 1 (-2200 5250);
DOT 1 (-1975 4225);
FORCENOTE
FROM BMC
(-8625 5400) 0;
DISPLAY LEFT (-8625 5400);
DISPLAY 1.021277 (-8625 5400);
FORCENOTE
TO BMC
(-1200 4350) 0;
DISPLAY LEFT (-1200 4350);
DISPLAY 1.021277 (-1200 4350);
FORCENOTE
TO 2ND REDRIVER
(-6125 3925) 0;
DISPLAY LEFT (-6125 3925);
DISPLAY 1.021277 (-6125 3925);
FORCENOTE
FROM FPGA
(-8700 4275) 0;
DISPLAY LEFT (-8700 4275);
DISPLAY 1.021277 (-8700 4275);
FORCENOTE
TO 1ST REDRIVER
(-6075 5425) 0;
DISPLAY LEFT (-6075 5425);
DISPLAY 1.021277 (-6075 5425);
FORCENOTE
TO 2ND REDRIVER
(-6050 5050) 0;
DISPLAY LEFT (-6050 5050);
DISPLAY 1.021277 (-6050 5050);
FORCENOTE
TO 1ST REDRIVER
(-6150 4300) 0;
DISPLAY LEFT (-6150 4300);
DISPLAY 1.021277 (-6150 4300);
FORCENOTE
FROM 1ST REDRIVER
(-4150 4350) 0;
DISPLAY LEFT (-4150 4350);
DISPLAY 1.021277 (-4150 4350);
FORCENOTE
FROM 2ND REDRIVER
(-4200 4950) 0;
DISPLAY LEFT (-4200 4950);
DISPLAY 1.021277 (-4200 4950);
FORCENOTE
FROM 2ND REDRIVER
(-4175 3975) 0;
DISPLAY LEFT (-4175 3975);
DISPLAY 1.021277 (-4175 3975);
FORCENOTE
FROM 1ST REDRIVER
(-4175 5325) 0;
DISPLAY LEFT (-4175 5325);
DISPLAY 1.021277 (-4175 5325);
FORCENOTE
TO GPU FPGA
(-1400 5325) 0;
DISPLAY LEFT (-1400 5325);
DISPLAY 1.021277 (-1400 5325);
QUIT
